(kicad_pcb
	(version 20260206)
	(generator "pcbnew")
	(generator_version "10.0")
	(general
		(thickness 1.6)
		(legacy_teardrops no)
	)
	(paper "A4")
	(title_block
		(title "04192023_DAF0TMB3IC0_F0TG_MB_C_brd_V02_OCP.brd")
		(comment 1 "Grand Teton / footprints 4517-4523 of 8354")
	)
	(layers
		(0 "F.Cu" signal "TOP")
		(4 "In1.Cu" signal "GND")
		(6 "In2.Cu" signal "IN1")
		(8 "In3.Cu" signal "GND1")
		(10 "In4.Cu" signal "IN2")
		(12 "In5.Cu" signal "GND2")
		(14 "In6.Cu" signal "IN3")
		(16 "In7.Cu" signal "GND3")
		(18 "In8.Cu" signal "VCC")
		(20 "In9.Cu" signal "VCC1")
		(22 "In10.Cu" signal "GND4")
		(24 "In11.Cu" signal "IN4")
		(26 "In12.Cu" signal "GND5")
		(28 "In13.Cu" signal "IN5")
		(30 "In14.Cu" signal "GND6")
		(32 "In15.Cu" signal "IN6")
		(34 "In16.Cu" signal "GND7")
		(2 "B.Cu" signal "BOTTOM")
		(9 "F.Adhes" user "F.Adhesive")
		(11 "B.Adhes" user "B.Adhesive")
		(13 "F.Paste" user "Package Geometry/Pastemask Top")
		(15 "B.Paste" user "Package Geometry/Pastemask Bottom")
		(5 "F.SilkS" user "Ref Des/Silkscreen Top")
		(7 "B.SilkS" user "Ref Des/Silkscreen Bottom")
		(1 "F.Mask" user "Board Geometry/Soldermask Top")
		(3 "B.Mask" user "Board Geometry/Soldermask Bottom")
		(17 "Dwgs.User" user "User.Drawings")
		(19 "Cmts.User" user "User.Comments")
		(21 "Eco1.User" user "User.Eco1")
		(23 "Eco2.User" user "User.Eco2")
		(25 "Edge.Cuts" user "Board Geometry/Outline")
		(27 "Margin" user)
		(31 "F.CrtYd" user "Package Geometry/Place Bound Top")
		(29 "B.CrtYd" user "Package Geometry/Place Bound Bottom")
		(35 "F.Fab" user "Ref Des/Assembly Top")
		(33 "B.Fab" user "Ref Des/Assembly Bottom")
	)
	(footprint ""
		(layer "F.Cu")
		(at 106.934 -415.036 180)
		(property "Reference" "C84"
			(at 0 0 180)
			(layer "F.SilkS")
			(hide yes)
			(effects
				(font
					(size 1.27 1.27)
				)
			)
		)
		(property "Value" ""
			(at 0 0 180)
			(layer "F.Fab")
			(effects
				(font
					(size 1.27 1.27)
				)
			)
		)
		(duplicate_pad_numbers_are_jumpers no)
		(fp_line
			(start 0.7874 0.4064)
			(end -0.7874 0.4064)
			(stroke
				(width 0.1524)
				(type default)
			)
			(layer "F.SilkS")
		)
		(fp_line
			(start 0.7874 -0.4064)
			(end 0.7874 0.4064)
			(stroke
				(width 0.1524)
				(type default)
			)
			(layer "F.SilkS")
		)
		(fp_line
			(start -0.7874 0.4064)
			(end -0.7874 -0.4064)
			(stroke
				(width 0.1524)
				(type default)
			)
			(layer "F.SilkS")
		)
		(fp_line
			(start -0.7874 -0.4064)
			(end 0.7874 -0.4064)
			(stroke
				(width 0.1524)
				(type default)
			)
			(layer "F.SilkS")
		)
		(fp_line
			(start 0.67945 0.3048)
			(end 0.120396 0.3048)
			(stroke
				(width 0.1)
				(type default)
			)
			(layer "F.Fab")
		)
		(fp_line
			(start 0.67945 -0.3048)
			(end 0.67945 0.3048)
			(stroke
				(width 0.1)
				(type default)
			)
			(layer "F.Fab")
		)
		(fp_line
			(start 0.12065 -0.2794)
			(end 0.12065 -0.3048)
			(stroke
				(width 0.1)
				(type default)
			)
			(layer "F.Fab")
		)
		(fp_line
			(start 0.12065 -0.3048)
			(end 0.67945 -0.3048)
			(stroke
				(width 0.1)
				(type default)
			)
			(layer "F.Fab")
		)
		(fp_line
			(start 0.120396 0.3048)
			(end 0.120396 0.2794)
			(stroke
				(width 0.1)
				(type default)
			)
			(layer "F.Fab")
		)
		(fp_line
			(start 0.120396 0.2794)
			(end -0.12065 0.2794)
			(stroke
				(width 0.1)
				(type default)
			)
			(layer "F.Fab")
		)
		(fp_line
			(start -0.12065 0.3048)
			(end -0.67945 0.3048)
			(stroke
				(width 0.1)
				(type default)
			)
			(layer "F.Fab")
		)
		(fp_line
			(start -0.12065 0.2794)
			(end -0.12065 0.3048)
			(stroke
				(width 0.1)
				(type default)
			)
			(layer "F.Fab")
		)
		(fp_line
			(start -0.12065 -0.2794)
			(end 0.12065 -0.2794)
			(stroke
				(width 0.1)
				(type default)
			)
			(layer "F.Fab")
		)
		(fp_line
			(start -0.12065 -0.305054)
			(end -0.12065 -0.2794)
			(stroke
				(width 0.1)
				(type default)
			)
			(layer "F.Fab")
		)
		(fp_line
			(start -0.67945 0.3048)
			(end -0.67945 -0.305054)
			(stroke
				(width 0.1)
				(type default)
			)
			(layer "F.Fab")
		)
		(fp_line
			(start -0.67945 -0.305054)
			(end -0.12065 -0.305054)
			(stroke
				(width 0.1)
				(type default)
			)
			(layer "F.Fab")
		)
		(pad "1" smd circle
			(at -0.40005 0 180)
			(size 0 0)
			(layers "F.Cu" "F.Mask" "F.Paste")
			(net "P3V3_9ZXL045_P1_VDDR")
		)
		(pad "2" smd circle
			(at 0.40005 0 180)
			(size 0 0)
			(layers "F.Cu" "F.Mask" "F.Paste")
			(net "GND")
		)
	)
	(footprint ""
		(layer "F.Cu")
		(at 12.741148 -385.91109 180)
		(property "Reference" "PC6622"
			(at 0 0 180)
			(layer "F.SilkS")
			(hide yes)
			(effects
				(font
					(size 1.27 1.27)
				)
			)
		)
		(property "Value" ""
			(at 0 0 180)
			(layer "F.Fab")
			(effects
				(font
					(size 1.27 1.27)
				)
			)
		)
		(duplicate_pad_numbers_are_jumpers no)
		(fp_line
			(start 0.7874 0.4064)
			(end -0.7874 0.4064)
			(stroke
				(width 0.1524)
				(type default)
			)
			(layer "F.SilkS")
		)
		(fp_line
			(start 0.7874 -0.4064)
			(end 0.7874 0.4064)
			(stroke
				(width 0.1524)
				(type default)
			)
			(layer "F.SilkS")
		)
		(fp_line
			(start -0.7874 0.4064)
			(end -0.7874 -0.4064)
			(stroke
				(width 0.1524)
				(type default)
			)
			(layer "F.SilkS")
		)
		(fp_line
			(start -0.7874 -0.4064)
			(end 0.7874 -0.4064)
			(stroke
				(width 0.1524)
				(type default)
			)
			(layer "F.SilkS")
		)
		(fp_line
			(start 0.67945 0.3048)
			(end 0.120396 0.3048)
			(stroke
				(width 0.1)
				(type default)
			)
			(layer "F.Fab")
		)
		(fp_line
			(start 0.67945 -0.3048)
			(end 0.67945 0.3048)
			(stroke
				(width 0.1)
				(type default)
			)
			(layer "F.Fab")
		)
		(fp_line
			(start 0.12065 -0.2794)
			(end 0.12065 -0.3048)
			(stroke
				(width 0.1)
				(type default)
			)
			(layer "F.Fab")
		)
		(fp_line
			(start 0.12065 -0.3048)
			(end 0.67945 -0.3048)
			(stroke
				(width 0.1)
				(type default)
			)
			(layer "F.Fab")
		)
		(fp_line
			(start 0.120396 0.3048)
			(end 0.120396 0.2794)
			(stroke
				(width 0.1)
				(type default)
			)
			(layer "F.Fab")
		)
		(fp_line
			(start 0.120396 0.2794)
			(end -0.12065 0.2794)
			(stroke
				(width 0.1)
				(type default)
			)
			(layer "F.Fab")
		)
		(fp_line
			(start -0.12065 0.3048)
			(end -0.67945 0.3048)
			(stroke
				(width 0.1)
				(type default)
			)
			(layer "F.Fab")
		)
		(fp_line
			(start -0.12065 0.2794)
			(end -0.12065 0.3048)
			(stroke
				(width 0.1)
				(type default)
			)
			(layer "F.Fab")
		)
		(fp_line
			(start -0.12065 -0.2794)
			(end 0.12065 -0.2794)
			(stroke
				(width 0.1)
				(type default)
			)
			(layer "F.Fab")
		)
		(fp_line
			(start -0.12065 -0.305054)
			(end -0.12065 -0.2794)
			(stroke
				(width 0.1)
				(type default)
			)
			(layer "F.Fab")
		)
		(fp_line
			(start -0.67945 0.3048)
			(end -0.67945 -0.305054)
			(stroke
				(width 0.1)
				(type default)
			)
			(layer "F.Fab")
		)
		(fp_line
			(start -0.67945 -0.305054)
			(end -0.12065 -0.305054)
			(stroke
				(width 0.1)
				(type default)
			)
			(layer "F.Fab")
		)
		(pad "1" smd circle
			(at -0.40005 0 180)
			(size 0 0)
			(layers "F.Cu" "F.Mask" "F.Paste")
			(net "SW_P0V9_RETIMER_CPU1_SW1")
		)
		(pad "2" smd circle
			(at 0.40005 0 180)
			(size 0 0)
			(layers "F.Cu" "F.Mask" "F.Paste")
			(net "SW_P0V9_RETIMER_CPU1_SW1_RC")
		)
	)
	(footprint ""
		(layer "F.Cu")
		(at 17.32915 -68.128642 180)
		(property "Reference" "R1192"
			(at 0 0 180)
			(layer "F.SilkS")
			(hide yes)
			(effects
				(font
					(size 1.27 1.27)
				)
			)
		)
		(property "Value" ""
			(at 0 0 180)
			(layer "F.Fab")
			(effects
				(font
					(size 1.27 1.27)
				)
			)
		)
		(duplicate_pad_numbers_are_jumpers no)
		(fp_line
			(start 0.7874 0.4064)
			(end -0.7874 0.4064)
			(stroke
				(width 0.1524)
				(type default)
			)
			(layer "F.SilkS")
		)
		(fp_line
			(start 0.7874 -0.4064)
			(end 0.7874 0.4064)
			(stroke
				(width 0.1524)
				(type default)
			)
			(layer "F.SilkS")
		)
		(fp_line
			(start -0.7874 0.4064)
			(end -0.7874 -0.4064)
			(stroke
				(width 0.1524)
				(type default)
			)
			(layer "F.SilkS")
		)
		(fp_line
			(start -0.7874 -0.4064)
			(end 0.7874 -0.4064)
			(stroke
				(width 0.1524)
				(type default)
			)
			(layer "F.SilkS")
		)
		(fp_line
			(start 0.67945 0.3048)
			(end 0.120396 0.3048)
			(stroke
				(width 0.1)
				(type default)
			)
			(layer "F.Fab")
		)
		(fp_line
			(start 0.67945 -0.3048)
			(end 0.67945 0.3048)
			(stroke
				(width 0.1)
				(type default)
			)
			(layer "F.Fab")
		)
		(fp_line
			(start 0.12065 -0.2794)
			(end 0.12065 -0.3048)
			(stroke
				(width 0.1)
				(type default)
			)
			(layer "F.Fab")
		)
		(fp_line
			(start 0.12065 -0.3048)
			(end 0.67945 -0.3048)
			(stroke
				(width 0.1)
				(type default)
			)
			(layer "F.Fab")
		)
		(fp_line
			(start 0.120396 0.3048)
			(end 0.120396 0.2794)
			(stroke
				(width 0.1)
				(type default)
			)
			(layer "F.Fab")
		)
		(fp_line
			(start 0.120396 0.2794)
			(end -0.12065 0.2794)
			(stroke
				(width 0.1)
				(type default)
			)
			(layer "F.Fab")
		)
		(fp_line
			(start -0.12065 0.3048)
			(end -0.67945 0.3048)
			(stroke
				(width 0.1)
				(type default)
			)
			(layer "F.Fab")
		)
		(fp_line
			(start -0.12065 0.2794)
			(end -0.12065 0.3048)
			(stroke
				(width 0.1)
				(type default)
			)
			(layer "F.Fab")
		)
		(fp_line
			(start -0.12065 -0.2794)
			(end 0.12065 -0.2794)
			(stroke
				(width 0.1)
				(type default)
			)
			(layer "F.Fab")
		)
		(fp_line
			(start -0.12065 -0.305054)
			(end -0.12065 -0.2794)
			(stroke
				(width 0.1)
				(type default)
			)
			(layer "F.Fab")
		)
		(fp_line
			(start -0.67945 0.3048)
			(end -0.67945 -0.305054)
			(stroke
				(width 0.1)
				(type default)
			)
			(layer "F.Fab")
		)
		(fp_line
			(start -0.67945 -0.305054)
			(end -0.12065 -0.305054)
			(stroke
				(width 0.1)
				(type default)
			)
			(layer "F.Fab")
		)
		(pad "1" smd circle
			(at -0.40005 0 180)
			(size 0 0)
			(layers "F.Cu" "F.Mask" "F.Paste")
			(net "P3V3_AUX")
		)
		(pad "2" smd circle
			(at 0.40005 0 180)
			(size 0 0)
			(layers "F.Cu" "F.Mask" "F.Paste")
			(net "HP_LVC3_OCP_V3_2_PRSNT2_N")
		)
	)
	(footprint ""
		(layer "F.Cu")
		(at 333.215488 -402.548852 -90)
		(property "Reference" "R1020"
			(at 0 0 270)
			(layer "F.SilkS")
			(hide yes)
			(effects
				(font
					(size 1.27 1.27)
				)
			)
		)
		(property "Value" ""
			(at 0 0 270)
			(layer "F.Fab")
			(effects
				(font
					(size 1.27 1.27)
				)
			)
		)
		(duplicate_pad_numbers_are_jumpers no)
		(fp_line
			(start -0.32512 0.175006)
			(end -0.32512 -0.175006)
			(stroke
				(width 0.1)
				(type default)
			)
			(layer "F.Fab")
		)
		(fp_line
			(start 0.32512 0.175006)
			(end -0.32512 0.175006)
			(stroke
				(width 0.1)
				(type default)
			)
			(layer "F.Fab")
		)
		(fp_line
			(start -0.32512 -0.175006)
			(end 0.32512 -0.175006)
			(stroke
				(width 0.1)
				(type default)
			)
			(layer "F.Fab")
		)
		(fp_line
			(start 0.32512 -0.175006)
			(end 0.32512 0.175006)
			(stroke
				(width 0.1)
				(type default)
			)
			(layer "F.Fab")
		)
		(pad "1" smd rect
			(at -0.2667 0 270)
			(size 0.3048 0.381)
			(layers "F.Cu" "F.Mask" "F.Paste")
			(net "RST_RT_CPU0_P1_RESET_R_N")
		)
		(pad "2" smd rect
			(at 0.2667 0 90)
			(size 0.3048 0.381)
			(layers "F.Cu" "F.Mask" "F.Paste")
			(net "GND")
		)
	)
	(footprint ""
		(layer "F.Cu")
		(at 441.430156 -399.213578 90)
		(property "Reference" "PC6552"
			(at 0 0 90)
			(layer "F.SilkS")
			(hide yes)
			(effects
				(font
					(size 1.27 1.27)
				)
			)
		)
		(property "Value" ""
			(at 0 0 90)
			(layer "F.Fab")
			(effects
				(font
					(size 1.27 1.27)
				)
			)
		)
		(duplicate_pad_numbers_are_jumpers no)
		(fp_line
			(start 0.7874 -0.4064)
			(end 0.7874 -0.105156)
			(stroke
				(width 0.1524)
				(type default)
			)
			(layer "F.SilkS")
		)
		(fp_line
			(start -0.7874 -0.4064)
			(end 0.7874 -0.4064)
			(stroke
				(width 0.1524)
				(type default)
			)
			(layer "F.SilkS")
		)
		(fp_line
			(start 0.582422 0.4064)
			(end -0.7874 0.4064)
			(stroke
				(width 0.1524)
				(type default)
			)
			(layer "F.SilkS")
		)
		(fp_line
			(start -0.7874 0.4064)
			(end -0.7874 -0.4064)
			(stroke
				(width 0.1524)
				(type default)
			)
			(layer "F.SilkS")
		)
		(fp_line
			(start -0.12065 -0.305054)
			(end -0.12065 -0.2794)
			(stroke
				(width 0.1)
				(type default)
			)
			(layer "F.Fab")
		)
		(fp_line
			(start -0.67945 -0.305054)
			(end -0.12065 -0.305054)
			(stroke
				(width 0.1)
				(type default)
			)
			(layer "F.Fab")
		)
		(fp_line
			(start 0.67945 -0.3048)
			(end 0.67945 0.3048)
			(stroke
				(width 0.1)
				(type default)
			)
			(layer "F.Fab")
		)
		(fp_line
			(start 0.12065 -0.3048)
			(end 0.67945 -0.3048)
			(stroke
				(width 0.1)
				(type default)
			)
			(layer "F.Fab")
		)
		(fp_line
			(start 0.12065 -0.2794)
			(end 0.12065 -0.3048)
			(stroke
				(width 0.1)
				(type default)
			)
			(layer "F.Fab")
		)
		(fp_line
			(start -0.12065 -0.2794)
			(end 0.12065 -0.2794)
			(stroke
				(width 0.1)
				(type default)
			)
			(layer "F.Fab")
		)
		(fp_line
			(start 0.120396 0.2794)
			(end -0.12065 0.2794)
			(stroke
				(width 0.1)
				(type default)
			)
			(layer "F.Fab")
		)
		(fp_line
			(start -0.12065 0.2794)
			(end -0.12065 0.3048)
			(stroke
				(width 0.1)
				(type default)
			)
			(layer "F.Fab")
		)
		(fp_line
			(start 0.67945 0.3048)
			(end 0.120396 0.3048)
			(stroke
				(width 0.1)
				(type default)
			)
			(layer "F.Fab")
		)
		(fp_line
			(start 0.120396 0.3048)
			(end 0.120396 0.2794)
			(stroke
				(width 0.1)
				(type default)
			)
			(layer "F.Fab")
		)
		(fp_line
			(start -0.12065 0.3048)
			(end -0.67945 0.3048)
			(stroke
				(width 0.1)
				(type default)
			)
			(layer "F.Fab")
		)
		(fp_line
			(start -0.67945 0.3048)
			(end -0.67945 -0.305054)
			(stroke
				(width 0.1)
				(type default)
			)
			(layer "F.Fab")
		)
		(pad "1" smd circle
			(at -0.40005 0 90)
			(size 0 0)
			(layers "F.Cu" "F.Mask" "F.Paste")
			(net "P0V9_RETIMER_CPU0_VCC1")
		)
		(pad "2" smd circle
			(at 0.40005 0 90)
			(size 0 0)
			(layers "F.Cu" "F.Mask" "F.Paste")
			(net "GND")
		)
	)
	(footprint ""
		(layer "F.Cu")
		(at 196.469 -92.456)
		(property "Reference" "R8040"
			(at 0 0 0)
			(layer "F.SilkS")
			(hide yes)
			(effects
				(font
					(size 1.27 1.27)
				)
			)
		)
		(property "Value" ""
			(at 0 0 0)
			(layer "F.Fab")
			(effects
				(font
					(size 1.27 1.27)
				)
			)
		)
		(duplicate_pad_numbers_are_jumpers no)
		(fp_line
			(start -0.7874 -0.4064)
			(end 0.7874 -0.4064)
			(stroke
				(width 0.1524)
				(type default)
			)
			(layer "F.SilkS")
		)
		(fp_line
			(start -0.7874 0.4064)
			(end -0.7874 -0.4064)
			(stroke
				(width 0.1524)
				(type default)
			)
			(layer "F.SilkS")
		)
		(fp_line
			(start 0.7874 -0.4064)
			(end 0.7874 0.4064)
			(stroke
				(width 0.1524)
				(type default)
			)
			(layer "F.SilkS")
		)
		(fp_line
			(start 0.7874 0.4064)
			(end -0.7874 0.4064)
			(stroke
				(width 0.1524)
				(type default)
			)
			(layer "F.SilkS")
		)
		(fp_line
			(start -0.67945 -0.305054)
			(end -0.12065 -0.305054)
			(stroke
				(width 0.1)
				(type default)
			)
			(layer "F.Fab")
		)
		(fp_line
			(start -0.67945 0.3048)
			(end -0.67945 -0.305054)
			(stroke
				(width 0.1)
				(type default)
			)
			(layer "F.Fab")
		)
		(fp_line
			(start -0.12065 -0.305054)
			(end -0.12065 -0.2794)
			(stroke
				(width 0.1)
				(type default)
			)
			(layer "F.Fab")
		)
		(fp_line
			(start -0.12065 -0.2794)
			(end 0.12065 -0.2794)
			(stroke
				(width 0.1)
				(type default)
			)
			(layer "F.Fab")
		)
		(fp_line
			(start -0.12065 0.2794)
			(end -0.12065 0.3048)
			(stroke
				(width 0.1)
				(type default)
			)
			(layer "F.Fab")
		)
		(fp_line
			(start -0.12065 0.3048)
			(end -0.67945 0.3048)
			(stroke
				(width 0.1)
				(type default)
			)
			(layer "F.Fab")
		)
		(fp_line
			(start 0.120396 0.2794)
			(end -0.12065 0.2794)
			(stroke
				(width 0.1)
				(type default)
			)
			(layer "F.Fab")
		)
		(fp_line
			(start 0.120396 0.3048)
			(end 0.120396 0.2794)
			(stroke
				(width 0.1)
				(type default)
			)
			(layer "F.Fab")
		)
		(fp_line
			(start 0.12065 -0.3048)
			(end 0.67945 -0.3048)
			(stroke
				(width 0.1)
				(type default)
			)
			(layer "F.Fab")
		)
		(fp_line
			(start 0.12065 -0.2794)
			(end 0.12065 -0.3048)
			(stroke
				(width 0.1)
				(type default)
			)
			(layer "F.Fab")
		)
		(fp_line
			(start 0.67945 -0.3048)
			(end 0.67945 0.3048)
			(stroke
				(width 0.1)
				(type default)
			)
			(layer "F.Fab")
		)
		(fp_line
			(start 0.67945 0.3048)
			(end 0.120396 0.3048)
			(stroke
				(width 0.1)
				(type default)
			)
			(layer "F.Fab")
		)
		(pad "1" smd circle
			(at -0.40005 0)
			(size 0 0)
			(layers "F.Cu" "F.Mask" "F.Paste")
			(net "P3V3_AUX")
		)
		(pad "2" smd circle
			(at 0.40005 0)
			(size 0 0)
			(layers "F.Cu" "F.Mask" "F.Paste")
			(net "PWRGD_CHGL_CPU1")
		)
	)
	(footprint ""
		(layer "F.Cu")
		(at 90.209878 -145.90141)
		(property "Reference" "R8166"
			(at 0 0 0)
			(layer "F.SilkS")
			(hide yes)
			(effects
				(font
					(size 1.27 1.27)
				)
			)
		)
		(property "Value" ""
			(at 0 0 0)
			(layer "F.Fab")
			(effects
				(font
					(size 1.27 1.27)
				)
			)
		)
		(duplicate_pad_numbers_are_jumpers no)
		(fp_line
			(start -0.7874 -0.4064)
			(end 0.7874 -0.4064)
			(stroke
				(width 0.1524)
				(type default)
			)
			(layer "F.SilkS")
		)
		(fp_line
			(start -0.7874 0.4064)
			(end -0.7874 -0.4064)
			(stroke
				(width 0.1524)
				(type default)
			)
			(layer "F.SilkS")
		)
		(fp_line
			(start 0.7874 -0.4064)
			(end 0.7874 0.4064)
			(stroke
				(width 0.1524)
				(type default)
			)
			(layer "F.SilkS")
		)
		(fp_line
			(start 0.7874 0.4064)
			(end -0.7874 0.4064)
			(stroke
				(width 0.1524)
				(type default)
			)
			(layer "F.SilkS")
		)
		(fp_line
			(start -0.67945 -0.305054)
			(end -0.12065 -0.305054)
			(stroke
				(width 0.1)
				(type default)
			)
			(layer "F.Fab")
		)
		(fp_line
			(start -0.67945 0.3048)
			(end -0.67945 -0.305054)
			(stroke
				(width 0.1)
				(type default)
			)
			(layer "F.Fab")
		)
		(fp_line
			(start -0.12065 -0.305054)
			(end -0.12065 -0.2794)
			(stroke
				(width 0.1)
				(type default)
			)
			(layer "F.Fab")
		)
		(fp_line
			(start -0.12065 -0.2794)
			(end 0.12065 -0.2794)
			(stroke
				(width 0.1)
				(type default)
			)
			(layer "F.Fab")
		)
		(fp_line
			(start -0.12065 0.2794)
			(end -0.12065 0.3048)
			(stroke
				(width 0.1)
				(type default)
			)
			(layer "F.Fab")
		)
		(fp_line
			(start -0.12065 0.3048)
			(end -0.67945 0.3048)
			(stroke
				(width 0.1)
				(type default)
			)
			(layer "F.Fab")
		)
		(fp_line
			(start 0.120396 0.2794)
			(end -0.12065 0.2794)
			(stroke
				(width 0.1)
				(type default)
			)
			(layer "F.Fab")
		)
		(fp_line
			(start 0.120396 0.3048)
			(end 0.120396 0.2794)
			(stroke
				(width 0.1)
				(type default)
			)
			(layer "F.Fab")
		)
		(fp_line
			(start 0.12065 -0.3048)
			(end 0.67945 -0.3048)
			(stroke
				(width 0.1)
				(type default)
			)
			(layer "F.Fab")
		)
		(fp_line
			(start 0.12065 -0.2794)
			(end 0.12065 -0.3048)
			(stroke
				(width 0.1)
				(type default)
			)
			(layer "F.Fab")
		)
		(fp_line
			(start 0.67945 -0.3048)
			(end 0.67945 0.3048)
			(stroke
				(width 0.1)
				(type default)
			)
			(layer "F.Fab")
		)
		(fp_line
			(start 0.67945 0.3048)
			(end 0.120396 0.3048)
			(stroke
				(width 0.1)
				(type default)
			)
			(layer "F.Fab")
		)
		(pad "1" smd circle
			(at -0.40005 0)
			(size 0 0)
			(layers "F.Cu" "F.Mask" "F.Paste")
			(net "PWRGD_PVDDCR_SOC_P1")
		)
		(pad "2" smd circle
			(at 0.40005 0)
			(size 0 0)
			(layers "F.Cu" "F.Mask" "F.Paste")
			(net "PWRGD_PVDDCR_SOC_P1_R")
		)
	)
)
